(kicad_pcb
	(version 20260206)
	(generator "pcbnew")
	(generator_version "10.0")
	(general
		(thickness 1.6)
		(legacy_teardrops no)
	)
	(paper "A4")
	(title_block
		(title "Bryce Canyon_IOM_M2_16342-2_OCP.brd")
		(comment 1 "Bryce Canyon / footprints 221-226 of 1146")
	)
	(layers
		(0 "F.Cu" signal "TOP")
		(4 "In1.Cu" signal "L2GND")
		(6 "In2.Cu" signal "L3")
		(8 "In3.Cu" signal "L4VCC")
		(10 "In4.Cu" signal "L5VCC")
		(12 "In5.Cu" signal "L6")
		(14 "In6.Cu" signal "L7GND")
		(2 "B.Cu" signal "BOTTOM")
		(9 "F.Adhes" user "F.Adhesive")
		(11 "B.Adhes" user "B.Adhesive")
		(13 "F.Paste" user "Package Geometry/Pastemask Top")
		(15 "B.Paste" user "Package Geometry/Pastemask Bottom")
		(5 "F.SilkS" user "Ref Des/Silkscreen Top")
		(7 "B.SilkS" user "Ref Des/Silkscreen Bottom")
		(1 "F.Mask" user "Board Geometry/Soldermask Top")
		(3 "B.Mask" user "Board Geometry/Soldermask Bottom")
		(17 "Dwgs.User" user "User.Drawings")
		(19 "Cmts.User" user "User.Comments")
		(21 "Eco1.User" user "User.Eco1")
		(23 "Eco2.User" user "User.Eco2")
		(25 "Edge.Cuts" user "Board Geometry/Outline")
		(27 "Margin" user)
		(31 "F.CrtYd" user "Package Geometry/Place Bound Top")
		(29 "B.CrtYd" user "Package Geometry/Place Bound Bottom")
		(35 "F.Fab" user "Ref Des/Assembly Top")
		(33 "B.Fab" user "Ref Des/Assembly Bottom")
	)
	(footprint ""
		(layer "F.Cu")
		(at 33.1216 -131.5212)
		(property "Reference" "OSC1"
			(at 0 0 0)
			(layer "F.SilkS")
			(hide yes)
			(effects
				(font
					(size 1.27 1.27)
				)
			)
		)
		(property "Value" "OSC-24MHZ-18-GP"
			(at 0.0127 -2.7686 0)
			(unlocked yes)
			(layer "F.Fab")
			(hide yes)
			(effects
				(font
					(size 1.016 1.016)
					(thickness 0.1524)
				)
			)
		)
		(property "Device Type" "OSC-3225-4P-3H48"
			(at 0.0127 -4.2926 0)
			(unlocked yes)
			(layer "F.Fab")
			(hide yes)
			(effects
				(font
					(size 1.016 1.016)
					(thickness 0.1524)
				)
			)
		)
		(duplicate_pad_numbers_are_jumpers no)
		(fp_line
			(start -2.2352 1.6256)
			(end -2.2352 0.635)
			(stroke
				(width 0.3302)
				(type default)
			)
			(layer "F.SilkS")
		)
		(fp_line
			(start -2.1209 -1.5367)
			(end 2.1209 -1.5367)
			(stroke
				(width 0.1524)
				(type default)
			)
			(layer "F.SilkS")
		)
		(fp_line
			(start -2.1209 1.5367)
			(end -2.1209 -1.5367)
			(stroke
				(width 0.1524)
				(type default)
			)
			(layer "F.SilkS")
		)
		(fp_line
			(start -1.3208 1.6256)
			(end -2.2352 1.6256)
			(stroke
				(width 0.3302)
				(type default)
			)
			(layer "F.SilkS")
		)
		(fp_line
			(start 2.1209 -1.5367)
			(end 2.1209 1.5367)
			(stroke
				(width 0.1524)
				(type default)
			)
			(layer "F.SilkS")
		)
		(fp_line
			(start 2.1209 1.5367)
			(end -2.1209 1.5367)
			(stroke
				(width 0.1524)
				(type default)
			)
			(layer "F.SilkS")
		)
		(fp_poly
			(pts
				(xy -3.7211 1.840992) (xy -3.7211 0.570992) (xy -3.0861 1.205992)
			)
			(stroke
				(width 0)
				(type default)
			)
			(fill yes)
			(layer "F.SilkS")
		)
		(fp_rect
			(start -1.6002 1.2446)
			(end 1.6002 -1.2446)
			(stroke
				(width 0)
				(type default)
			)
			(fill no)
			(layer "F.CrtYd")
		)
		(fp_poly
			(pts
				(xy -2.3749 1.7907) (xy -2.3749 -1.7907) (xy 2.3749 -1.7907) (xy 2.3749 1.7907) (xy 1.6002 1.7907)
				(xy 1.6002 -1.2446) (xy -1.6002 -1.2446) (xy -1.6002 1.2446) (xy 1.59512 1.2446) (xy 1.59512 1.7907)
			)
			(stroke
				(width 0)
				(type default)
			)
			(fill no)
			(layer "F.CrtYd")
		)
		(fp_rect
			(start -2.3749 1.7907)
			(end 2.3749 -1.7907)
			(stroke
				(width 0)
				(type default)
			)
			(fill no)
			(layer "F.Fab")
		)
		(pad "1" smd rect
			(at -1.171448 0.824992)
			(size 1.397 0.9144)
			(layers "F.Cu" "F.Mask" "F.Paste")
			(net "OSC_OE")
		)
		(pad "2" smd rect
			(at 1.171448 0.824992)
			(size 1.397 0.9144)
			(layers "F.Cu" "F.Mask" "F.Paste")
			(net "GND")
		)
		(pad "3" smd rect
			(at 1.171448 -0.824992)
			(size 1.397 0.9144)
			(layers "F.Cu" "F.Mask" "F.Paste")
			(net "OSC_OUT")
		)
		(pad "4" smd rect
			(at -1.171448 -0.824992)
			(size 1.397 0.9144)
			(layers "F.Cu" "F.Mask" "F.Paste")
			(net "P3V3_STBY")
		)
		(zone
			(layer "F.Cu")
			(hatch none 0.5)
			(connect_pads
				(clearance 0)
			)
			(min_thickness 0.25)
			(keepout
				(tracks not_allowed)
				(vias allowed)
				(pads allowed)
				(copperpour not_allowed)
				(footprints allowed)
			)
			(placement
				(enabled no)
				(sheetname "")
			)
			(fill
				(thermal_gap 0.5)
				(thermal_bridge_width 0.5)
				(island_removal_mode 0)
			)
			(polygon
				(pts
					(xy 32.973772 -131.478528) (xy 33.269428 -131.478528) (xy 33.269428 -131.563872) (xy 32.973772 -131.563872)
				)
			)
		)
		(zone
			(layer "F.Cu")
			(hatch none 0.5)
			(connect_pads
				(clearance 0)
			)
			(min_thickness 0.25)
			(keepout
				(tracks allowed)
				(vias not_allowed)
				(pads allowed)
				(copperpour not_allowed)
				(footprints allowed)
			)
			(placement
				(enabled no)
				(sheetname "")
			)
			(fill
				(thermal_gap 0.5)
				(thermal_bridge_width 0.5)
				(island_removal_mode 0)
			)
			(polygon
				(pts
					(xy 32.648652 -130.239008) (xy 32.648652 -131.153408) (xy 31.251652 -131.153408) (xy 31.251652 -131.888992)
					(xy 32.648652 -131.888992) (xy 32.648652 -132.803392) (xy 33.594548 -132.803392) (xy 33.594548 -131.888992)
					(xy 34.991548 -131.888992) (xy 34.991548 -131.153408) (xy 33.594548 -131.153408) (xy 33.594548 -130.239008)
				)
			)
		)
	)
	(footprint ""
		(layer "F.Cu")
		(at 199.1868 -7.5692 -90)
		(property "Reference" "R817"
			(at 0 0 270)
			(layer "F.SilkS")
			(hide yes)
			(effects
				(font
					(size 1.27 1.27)
				)
			)
		)
		(property "Value" "130R3F-GP"
			(at -0.0254 -2.5146 270)
			(unlocked yes)
			(layer "F.Fab")
			(hide yes)
			(effects
				(font
					(size 1.016 1.016)
					(thickness 0.1524)
				)
			)
		)
		(property "Device Type" "R603H22"
			(at -0.0254 -4.0386 270)
			(unlocked yes)
			(layer "F.Fab")
			(hide yes)
			(effects
				(font
					(size 1.016 1.016)
					(thickness 0.1524)
				)
			)
		)
		(duplicate_pad_numbers_are_jumpers no)
		(fp_line
			(start -0.4826 0)
			(end -0.2032 0)
			(stroke
				(width 0.2032)
				(type default)
			)
			(layer "F.SilkS")
		)
		(fp_line
			(start 0.2032 0)
			(end 0.4826 0)
			(stroke
				(width 0.2032)
				(type default)
			)
			(layer "F.SilkS")
		)
		(fp_rect
			(start -0.5842 1.3335)
			(end 0.5842 -1.3335)
			(stroke
				(width 0)
				(type default)
			)
			(fill no)
			(layer "F.CrtYd")
		)
		(fp_rect
			(start -0.5842 1.3335)
			(end 0.5842 -1.3335)
			(stroke
				(width 0)
				(type default)
			)
			(fill no)
			(layer "F.Fab")
		)
		(pad "1" smd custom
			(at 0 -0.762 270)
			(size 0.2159 0.2159)
			(layers "F.Cu" "F.Mask" "F.Paste")
			(net "ML_PWR_BLUE_LED_R")
			(options
				(clearance outline)
				(anchor circle)
			)
			(primitives
				(gr_poly
					(pts
						(arc
							(start -0.3302 -0.4318)
							(mid -0.402042 -0.402042)
							(end -0.4318 -0.3302)
						)
						(arc
							(start -0.4318 0.3302)
							(mid -0.402042 0.402042)
							(end -0.3302 0.4318)
						)
						(arc
							(start 0.3302 0.4318)
							(mid 0.402042 0.402042)
							(end 0.4318 0.3302)
						)
						(arc
							(start 0.4318 -0.3302)
							(mid 0.402042 -0.402042)
							(end 0.3302 -0.4318)
						)
					)
					(width 0)
					(fill yes)
				)
			)
		)
		(pad "2" smd custom
			(at 0 0.762 270)
			(size 0.2159 0.2159)
			(layers "F.Cu" "F.Mask" "F.Paste")
			(net "ML_PWR_BLUE_LED")
			(options
				(clearance outline)
				(anchor circle)
			)
			(primitives
				(gr_poly
					(pts
						(arc
							(start -0.3302 -0.4318)
							(mid -0.402042 -0.402042)
							(end -0.4318 -0.3302)
						)
						(arc
							(start -0.4318 0.3302)
							(mid -0.402042 0.402042)
							(end -0.3302 0.4318)
						)
						(arc
							(start 0.3302 0.4318)
							(mid 0.402042 0.402042)
							(end 0.4318 0.3302)
						)
						(arc
							(start 0.4318 -0.3302)
							(mid 0.402042 -0.402042)
							(end 0.3302 -0.4318)
						)
					)
					(width 0)
					(fill yes)
				)
			)
		)
	)
	(footprint ""
		(layer "F.Cu")
		(at 137.73023 -12.991592 180)
		(property "Reference" "R444"
			(at 0 0 180)
			(layer "F.SilkS")
			(hide yes)
			(effects
				(font
					(size 1.27 1.27)
				)
			)
		)
		(property "Value" "D002RL3115F-L-GP"
			(at 3.2258 1.2954 180)
			(unlocked yes)
			(layer "F.Fab")
			(hide yes)
			(effects
				(font
					(size 1.016 1.016)
					(thickness 0.1524)
				)
			)
		)
		(property "Device Type" "RL3115-4PH45"
			(at 3.2258 -0.2286 180)
			(unlocked yes)
			(layer "F.Fab")
			(hide yes)
			(effects
				(font
					(size 1.016 1.016)
					(thickness 0.1524)
				)
			)
		)
		(duplicate_pad_numbers_are_jumpers no)
		(fp_line
			(start 1.9685 1.651)
			(end -1.9685 1.651)
			(stroke
				(width 0.1524)
				(type default)
			)
			(layer "F.SilkS")
		)
		(fp_line
			(start 1.9685 -1.651)
			(end 1.9685 1.651)
			(stroke
				(width 0.1524)
				(type default)
			)
			(layer "F.SilkS")
		)
		(fp_line
			(start -0.5334 -1.7653)
			(end -2.0574 -1.7653)
			(stroke
				(width 0.3302)
				(type default)
			)
			(layer "F.SilkS")
		)
		(fp_line
			(start -1.9685 1.651)
			(end -1.9685 -1.651)
			(stroke
				(width 0.1524)
				(type default)
			)
			(layer "F.SilkS")
		)
		(fp_line
			(start -1.9685 -1.651)
			(end 1.9685 -1.651)
			(stroke
				(width 0.1524)
				(type default)
			)
			(layer "F.SilkS")
		)
		(fp_line
			(start -2.0574 -1.7653)
			(end -2.0574 -0.4064)
			(stroke
				(width 0.3302)
				(type default)
			)
			(layer "F.SilkS")
		)
		(fp_poly
			(pts
				(xy -2.29997 -1.016) (xy -2.80797 -1.524) (xy -2.80797 -0.508)
			)
			(stroke
				(width 0)
				(type default)
			)
			(fill yes)
			(layer "F.SilkS")
		)
		(fp_rect
			(start -1.524 0.7493)
			(end 1.524 -0.7493)
			(stroke
				(width 0)
				(type default)
			)
			(fill no)
			(layer "F.CrtYd")
		)
		(fp_poly
			(pts
				(xy -2.2225 1.905) (xy -2.2225 -1.905) (xy 2.2225 -1.905) (xy 2.2225 -0.7493) (xy -1.524 -0.7493)
				(xy -1.524 0.7493) (xy 1.524 0.7493) (xy 1.524 -0.7366) (xy 2.2225 -0.7366) (xy 2.2225 1.905)
			)
			(stroke
				(width 0)
				(type default)
			)
			(fill no)
			(layer "F.CrtYd")
		)
		(fp_rect
			(start -2.2225 1.905)
			(end 2.2225 -1.905)
			(stroke
				(width 0)
				(type default)
			)
			(fill no)
			(layer "F.Fab")
		)
		(pad "1" smd rect
			(at -0.5715 -0.813562 180)
			(size 2.286 1.143)
			(layers "F.Cu" "F.Mask" "F.Paste")
			(net "MB0_P12V_MAIN_R")
		)
		(pad "2" smd rect
			(at -0.5715 0.813562 180)
			(size 2.286 1.143)
			(layers "F.Cu" "F.Mask" "F.Paste")
			(net "P12V_IOM")
		)
		(pad "3" smd rect
			(at 1.334008 -0.813562 180)
			(size 0.762 1.143)
			(layers "F.Cu" "F.Mask" "F.Paste")
			(net "MB0_CM_SENSE_R1_N")
		)
		(pad "4" smd rect
			(at 1.334008 0.813562 180)
			(size 0.762 1.143)
			(layers "F.Cu" "F.Mask" "F.Paste")
			(net "MB0_CM_SENSE_R1_P")
		)
		(zone
			(layer "F.Cu")
			(hatch none 0.5)
			(connect_pads
				(clearance 0)
			)
			(min_thickness 0.25)
			(keepout
				(tracks not_allowed)
				(vias allowed)
				(pads allowed)
				(copperpour not_allowed)
				(footprints allowed)
			)
			(placement
				(enabled no)
				(sheetname "")
			)
			(fill
				(thermal_gap 0.5)
				(thermal_bridge_width 0.5)
				(island_removal_mode 0)
			)
			(polygon
				(pts
					(xy 137.15873 -13.740892) (xy 136.777222 -13.740892) (xy 136.777222 -13.233654) (xy 137.15873 -13.233654)
				)
			)
		)
		(zone
			(layer "F.Cu")
			(hatch none 0.5)
			(connect_pads
				(clearance 0)
			)
			(min_thickness 0.25)
			(keepout
				(tracks allowed)
				(vias not_allowed)
				(pads allowed)
				(copperpour not_allowed)
				(footprints allowed)
			)
			(placement
				(enabled no)
				(sheetname "")
			)
			(fill
				(thermal_gap 0.5)
				(thermal_bridge_width 0.5)
				(island_removal_mode 0)
			)
			(polygon
				(pts
					(xy 137.15873 -13.740892) (xy 136.777222 -13.740892) (xy 136.777222 -13.233654) (xy 137.15873 -13.233654)
				)
			)
		)
		(zone
			(layer "F.Cu")
			(hatch none 0.5)
			(connect_pads
				(clearance 0)
			)
			(min_thickness 0.25)
			(keepout
				(tracks not_allowed)
				(vias allowed)
				(pads allowed)
				(copperpour not_allowed)
				(footprints allowed)
			)
			(placement
				(enabled no)
				(sheetname "")
			)
			(fill
				(thermal_gap 0.5)
				(thermal_bridge_width 0.5)
				(island_removal_mode 0)
			)
			(polygon
				(pts
					(xy 137.15873 -12.74953) (xy 136.777222 -12.74953) (xy 136.777222 -12.242292) (xy 137.15873 -12.242292)
				)
			)
		)
		(zone
			(layer "F.Cu")
			(hatch none 0.5)
			(connect_pads
				(clearance 0)
			)
			(min_thickness 0.25)
			(keepout
				(tracks allowed)
				(vias not_allowed)
				(pads allowed)
				(copperpour not_allowed)
				(footprints allowed)
			)
			(placement
				(enabled no)
				(sheetname "")
			)
			(fill
				(thermal_gap 0.5)
				(thermal_bridge_width 0.5)
				(island_removal_mode 0)
			)
			(polygon
				(pts
					(xy 137.15873 -12.74953) (xy 136.777222 -12.74953) (xy 136.777222 -12.242292) (xy 137.15873 -12.242292)
				)
			)
		)
	)
	(footprint ""
		(layer "F.Cu")
		(at 179.2986 -107.6452 -90)
		(property "Reference" "C601"
			(at 0 0 270)
			(layer "F.SilkS")
			(hide yes)
			(effects
				(font
					(size 1.27 1.27)
				)
			)
		)
		(property "Value" "SCD1U16V2KX-3GP"
			(at 1.1811 -2.7051 270)
			(unlocked yes)
			(layer "F.Fab")
			(hide yes)
			(effects
				(font
					(size 1.016 1.016)
					(thickness 0.1524)
				)
			)
		)
		(property "Device Type" "C402H22"
			(at 1.1811 -4.2291 270)
			(unlocked yes)
			(layer "F.Fab")
			(hide yes)
			(effects
				(font
					(size 1.016 1.016)
					(thickness 0.1524)
				)
			)
		)
		(duplicate_pad_numbers_are_jumpers no)
		(fp_rect
			(start -0.4318 0.9525)
			(end 0.4318 -0.9525)
			(stroke
				(width 0)
				(type default)
			)
			(fill no)
			(layer "F.CrtYd")
		)
		(fp_rect
			(start -0.4318 0.9525)
			(end 0.4318 -0.9525)
			(stroke
				(width 0)
				(type default)
			)
			(fill no)
			(layer "F.Fab")
		)
		(pad "1" smd custom
			(at 0 -0.4445 270)
			(size 0.1524 0.1524)
			(layers "F.Cu" "F.Mask" "F.Paste")
			(net "P3V3_STBY")
			(options
				(clearance outline)
				(anchor circle)
			)
			(primitives
				(gr_poly
					(pts
						(arc
							(start 0.3048 -0.2032)
							(mid 0.275042 -0.275042)
							(end 0.2032 -0.3048)
						)
						(arc
							(start -0.2032 -0.3048)
							(mid -0.275042 -0.275042)
							(end -0.3048 -0.2032)
						)
						(arc
							(start -0.3048 0.2032)
							(mid -0.275042 0.275042)
							(end -0.2032 0.3048)
						)
						(arc
							(start 0.2032 0.3048)
							(mid 0.275042 0.275042)
							(end 0.3048 0.2032)
						)
					)
					(width 0)
					(fill yes)
				)
			)
		)
		(pad "2" smd custom
			(at 0 0.4445 270)
			(size 0.1524 0.1524)
			(layers "F.Cu" "F.Mask" "F.Paste")
			(net "GND")
			(options
				(clearance outline)
				(anchor circle)
			)
			(primitives
				(gr_poly
					(pts
						(arc
							(start 0.3048 -0.2032)
							(mid 0.275042 -0.275042)
							(end 0.2032 -0.3048)
						)
						(arc
							(start -0.2032 -0.3048)
							(mid -0.275042 -0.275042)
							(end -0.3048 -0.2032)
						)
						(arc
							(start -0.3048 0.2032)
							(mid -0.275042 0.275042)
							(end -0.2032 0.3048)
						)
						(arc
							(start 0.2032 0.3048)
							(mid 0.275042 0.275042)
							(end 0.3048 0.2032)
						)
					)
					(width 0)
					(fill yes)
				)
			)
		)
	)
	(footprint ""
		(layer "F.Cu")
		(at 44.3738 -161.417 180)
		(property "Reference" "R187"
			(at 0 0 180)
			(layer "F.SilkS")
			(hide yes)
			(effects
				(font
					(size 1.27 1.27)
				)
			)
		)
		(property "Value" "2K2R2F-GP"
			(at 0.064008 -3.993896 180)
			(unlocked yes)
			(layer "F.Fab")
			(hide yes)
			(effects
				(font
					(size 1.016 1.016)
					(thickness 0.1524)
				)
			)
		)
		(property "Device Type" "R402H16"
			(at 0.064008 -5.517896 180)
			(unlocked yes)
			(layer "F.Fab")
			(hide yes)
			(effects
				(font
					(size 1.016 1.016)
					(thickness 0.1524)
				)
			)
		)
		(duplicate_pad_numbers_are_jumpers no)
		(fp_line
			(start 0.508 -0.9398)
			(end -0.508 -0.9398)
			(stroke
				(width 0.1524)
				(type default)
			)
			(layer "F.SilkS")
		)
		(fp_line
			(start -0.508 -0.9398)
			(end -0.508 0.9398)
			(stroke
				(width 0.1524)
				(type default)
			)
			(layer "F.SilkS")
		)
		(fp_rect
			(start -0.508 0.9398)
			(end 0.508 -0.9398)
			(stroke
				(width 0)
				(type default)
			)
			(fill no)
			(layer "F.CrtYd")
		)
		(fp_rect
			(start -0.508 0.9398)
			(end 0.508 -0.9398)
			(stroke
				(width 0)
				(type default)
			)
			(fill no)
			(layer "F.Fab")
		)
		(pad "1" smd custom
			(at 0 -0.4445 180)
			(size 0.1397 0.1397)
			(layers "F.Cu" "F.Mask" "F.Paste")
			(net "I2C_M2_1_SCL")
			(options
				(clearance outline)
				(anchor circle)
			)
			(primitives
				(gr_poly
					(pts
						(arc
							(start -0.1778 -0.2794)
							(mid -0.249642 -0.249642)
							(end -0.2794 -0.1778)
						)
						(arc
							(start -0.2794 0.1778)
							(mid -0.249642 0.249642)
							(end -0.1778 0.2794)
						)
						(arc
							(start 0.1778 0.2794)
							(mid 0.249642 0.249642)
							(end 0.2794 0.1778)
						)
						(arc
							(start 0.2794 -0.1778)
							(mid 0.249642 -0.249642)
							(end 0.1778 -0.2794)
						)
					)
					(width 0)
					(fill yes)
				)
			)
		)
		(pad "2" smd custom
			(at 0 0.4445 180)
			(size 0.1397 0.1397)
			(layers "F.Cu" "F.Mask" "F.Paste")
			(net "P3V3_STBY")
			(options
				(clearance outline)
				(anchor circle)
			)
			(primitives
				(gr_poly
					(pts
						(arc
							(start -0.1778 -0.2794)
							(mid -0.249642 -0.249642)
							(end -0.2794 -0.1778)
						)
						(arc
							(start -0.2794 0.1778)
							(mid -0.249642 0.249642)
							(end -0.1778 0.2794)
						)
						(arc
							(start 0.1778 0.2794)
							(mid 0.249642 0.249642)
							(end 0.2794 0.1778)
						)
						(arc
							(start 0.2794 -0.1778)
							(mid 0.249642 -0.249642)
							(end 0.1778 -0.2794)
						)
					)
					(width 0)
					(fill yes)
				)
			)
		)
	)
	(footprint ""
		(layer "F.Cu")
		(at 181.8894 -111.0234 180)
		(property "Reference" "R551"
			(at 0 0 180)
			(layer "F.SilkS")
			(hide yes)
			(effects
				(font
					(size 1.27 1.27)
				)
			)
		)
		(property "Value" "4K7R2F-GP"
			(at 0.064008 -3.993896 180)
			(unlocked yes)
			(layer "F.Fab")
			(hide yes)
			(effects
				(font
					(size 1.016 1.016)
					(thickness 0.1524)
				)
			)
		)
		(property "Device Type" "R402H16"
			(at 0.064008 -5.517896 180)
			(unlocked yes)
			(layer "F.Fab")
			(hide yes)
			(effects
				(font
					(size 1.016 1.016)
					(thickness 0.1524)
				)
			)
		)
		(duplicate_pad_numbers_are_jumpers no)
		(fp_line
			(start 0.508 -0.9398)
			(end -0.508 -0.9398)
			(stroke
				(width 0.1524)
				(type default)
			)
			(layer "F.SilkS")
		)
		(fp_line
			(start -0.508 -0.9398)
			(end -0.508 0.9398)
			(stroke
				(width 0.1524)
				(type default)
			)
			(layer "F.SilkS")
		)
		(fp_rect
			(start -0.508 0.9398)
			(end 0.508 -0.9398)
			(stroke
				(width 0)
				(type default)
			)
			(fill no)
			(layer "F.CrtYd")
		)
		(fp_rect
			(start -0.508 0.9398)
			(end 0.508 -0.9398)
			(stroke
				(width 0)
				(type default)
			)
			(fill no)
			(layer "F.Fab")
		)
		(pad "1" smd custom
			(at 0 -0.4445 180)
			(size 0.1397 0.1397)
			(layers "F.Cu" "F.Mask" "F.Paste")
			(net "TEMP_1_A0")
			(options
				(clearance outline)
				(anchor circle)
			)
			(primitives
				(gr_poly
					(pts
						(arc
							(start -0.1778 -0.2794)
							(mid -0.249642 -0.249642)
							(end -0.2794 -0.1778)
						)
						(arc
							(start -0.2794 0.1778)
							(mid -0.249642 0.249642)
							(end -0.1778 0.2794)
						)
						(arc
							(start 0.1778 0.2794)
							(mid 0.249642 0.249642)
							(end 0.2794 0.1778)
						)
						(arc
							(start 0.2794 -0.1778)
							(mid 0.249642 -0.249642)
							(end 0.1778 -0.2794)
						)
					)
					(width 0)
					(fill yes)
				)
			)
		)
		(pad "2" smd custom
			(at 0 0.4445 180)
			(size 0.1397 0.1397)
			(layers "F.Cu" "F.Mask" "F.Paste")
			(net "GND")
			(options
				(clearance outline)
				(anchor circle)
			)
			(primitives
				(gr_poly
					(pts
						(arc
							(start -0.1778 -0.2794)
							(mid -0.249642 -0.249642)
							(end -0.2794 -0.1778)
						)
						(arc
							(start -0.2794 0.1778)
							(mid -0.249642 0.249642)
							(end -0.1778 0.2794)
						)
						(arc
							(start 0.1778 0.2794)
							(mid 0.249642 0.249642)
							(end 0.2794 0.1778)
						)
						(arc
							(start 0.2794 -0.1778)
							(mid 0.249642 -0.249642)
							(end 0.1778 -0.2794)
						)
					)
					(width 0)
					(fill yes)
				)
			)
		)
	)
)
